# Knox_DRIVE PLANE BOARD_8Layer_Stackup_20120614_EE_v5.xlsx — Wistron (pcb-stackup)
| Board Number: |  | 12432-SB |  |  |  |  |  |  |  |
| Model Name: |  | KNOX DPB |  |  |  |  |  |  |  |
| Layer Count: |  | 8 Layer |  |  |  |  |  |  |  |
| Date: |  | 41074 |  |  |  |  |  |  |  |
| Material: |  | FR-4 (Lead-Free, OSP, High Tg) |  |  |  | Single End |  | Differential |  |
| CCL/PP type: |  | TU722+RTF |  |  | Imp | 50 | Imp | 100 |  |
| Customer: |  | <name> |  |  | Variation | Inner 10% / Outer 15% | Variation | Inner 10% / Outer 15% |  |
| EE Engineer: |  | <name> |  |  | Bus | Misc.I/O | Bus | SAS/SATA |  |
| SI Engineer: |  | <name> |  |  |  |  |  |  |  |
|  |  |  |  |  | Type | SE | Type | DP |  |
| Layer |  |  | Thickness | Er | Layers | 1,3,6,8 | Layers | 1,3,6,8 |  |
|  |  | Cu oz | Wistron | Wistron |  | Wistron |  | Wistron |  |
|  | Mask |  | 0.5 | 3.8 |  | Width |  | Width | Space |
| S1 | Signal | 1.5 | 1.9 |  | S1 | 4 | S1 | 4 | 9 |
|  | Prepreg |  | 2.7 | 3.5 |  |  |  |  |  |
| P2 | GND | 2 oz | 2.6 |  | P2 |  | P2 |  |  |
|  | Core |  | 4 | 3.7 |  |  |  |  |  |
| S3 | Signal | 1 oz | 1.3 |  | S3 | 4.5 | S3 | 4 | 8 |
|  | Prepreg |  | 25 | 4.4000000000000004 |  |  |  |  |  |
| P4 | PWR | 2 oz | 2.6 |  | P4 |  | P4 |  |  |
|  | Core |  | 4 | 4.0999999999999996 |  |  |  |  |  |
| P5 | PWR | 2 oz | 2.6 |  | P5 |  | P5 |  |  |
|  | Prepreg |  | 25 | 4.4000000000000004 |  |  |  |  |  |
| S6 | Signal | 1 oz | 1.3 |  | S6 | 4.5 | S6 | 4 | 8 |
|  | Core |  | 4 | 3.7 |  |  |  |  |  |
| P7 | GND | 2 oz | 2.6 |  | P7 |  | P7 |  |  |
|  | Prepreg |  | 2.7 | 3.5 |  |  |  |  |  |
| S8 | Signal | 1.5 | 1.9 |  | S8 | 4 | S8 | 4 | 9 |
|  | Mask |  | 0.5 | 3.8 |  |  |  |  |  |
| Target= 85mil |  |  |  |  |  |  |  |  |  |
| Note: | 1. Unit is mil |  |  |  |  |  |  |  |  |
|  | 2. The variation of total thickness is +/- 10% |  |  |  |  |  |  |  |  |
|  | 3. The total thickness includes trace and solder mask , not G/F  area |  |  |  |  |  |  |  |  |
|  | 4. Min hole copper thickness is 1.0 mil |  |  |  |  |  |  |  |  |
|  | 5. Min surface copper thickness 1.5 mil |  |  |  |  |  |  |  |  |
